(kicad_pcb
	(version 20260206)
	(generator "pcbnew")
	(generator_version "10.0")
	(general
		(thickness 1.6)
		(legacy_teardrops no)
	)
	(paper "A4")
	(title_block
		(title "peb — Lightning_PEB_BRD.brd")
		(comment 1 "Lightning (Wiwynn / Facebook NVMe JBOF) / footprints 821-826 of 2563")
	)
	(layers
		(0 "F.Cu" signal "TOP")
		(4 "In1.Cu" signal "L2GND")
		(6 "In2.Cu" signal "L3")
		(8 "In3.Cu" signal "L4VCC")
		(10 "In4.Cu" signal "L5VCC")
		(12 "In5.Cu" signal "L6")
		(14 "In6.Cu" signal "L7GND")
		(2 "B.Cu" signal "BOTTOM")
		(9 "F.Adhes" user "F.Adhesive")
		(11 "B.Adhes" user "B.Adhesive")
		(13 "F.Paste" user "Package Geometry/Pastemask Top")
		(15 "B.Paste" user "Package Geometry/Pastemask Bottom")
		(5 "F.SilkS" user "Ref Des/Silkscreen Top")
		(7 "B.SilkS" user "Ref Des/Silkscreen Bottom")
		(1 "F.Mask" user "Board Geometry/Soldermask Top")
		(3 "B.Mask" user "Board Geometry/Soldermask Bottom")
		(17 "Dwgs.User" user "User.Drawings")
		(19 "Cmts.User" user "User.Comments")
		(21 "Eco1.User" user "User.Eco1")
		(23 "Eco2.User" user "User.Eco2")
		(25 "Edge.Cuts" user "Board Geometry/Outline")
		(27 "Margin" user)
		(31 "F.CrtYd" user "Package Geometry/Place Bound Top")
		(29 "B.CrtYd" user "Package Geometry/Place Bound Bottom")
		(35 "F.Fab" user "Ref Des/Assembly Top")
		(33 "B.Fab" user "Ref Des/Assembly Bottom")
	)
	(footprint ""
		(layer "F.Cu")
		(at 14.5288 -173.9138 180)
		(property "Reference" "R664"
			(at 0 0 180)
			(layer "F.SilkS")
			(hide yes)
			(effects
				(font
					(size 1.27 1.27)
				)
			)
		)
		(property "Value" "27KR2F-L-GP"
			(at 0.064008 -3.993896 180)
			(unlocked yes)
			(layer "F.Fab")
			(hide yes)
			(effects
				(font
					(size 1.016 1.016)
					(thickness 0.1524)
				)
			)
		)
		(property "Device Type" "R402H16"
			(at 0.064008 -5.517896 180)
			(unlocked yes)
			(layer "F.Fab")
			(hide yes)
			(effects
				(font
					(size 1.016 1.016)
					(thickness 0.1524)
				)
			)
		)
		(duplicate_pad_numbers_are_jumpers no)
		(fp_line
			(start 0.508 -0.9398)
			(end -0.508 -0.9398)
			(stroke
				(width 0.1524)
				(type default)
			)
			(layer "F.SilkS")
		)
		(fp_line
			(start -0.508 -0.9398)
			(end -0.508 0.9398)
			(stroke
				(width 0.1524)
				(type default)
			)
			(layer "F.SilkS")
		)
		(fp_rect
			(start -0.508 0.9398)
			(end 0.508 -0.9398)
			(stroke
				(width 0)
				(type default)
			)
			(fill no)
			(layer "F.CrtYd")
		)
		(fp_rect
			(start -0.508 0.9398)
			(end 0.508 -0.9398)
			(stroke
				(width 0)
				(type default)
			)
			(fill no)
			(layer "F.Fab")
		)
		(pad "1" smd custom
			(at 0 -0.4445 180)
			(size 0.1397 0.1397)
			(layers "F.Cu" "F.Mask" "F.Paste")
			(net "P12V_PCIE")
			(options
				(clearance outline)
				(anchor circle)
			)
			(primitives
				(gr_poly
					(pts
						(arc
							(start -0.1778 -0.2794)
							(mid -0.249642 -0.249642)
							(end -0.2794 -0.1778)
						)
						(arc
							(start -0.2794 0.1778)
							(mid -0.249642 0.249642)
							(end -0.1778 0.2794)
						)
						(arc
							(start 0.1778 0.2794)
							(mid 0.249642 0.249642)
							(end 0.2794 0.1778)
						)
						(arc
							(start 0.2794 -0.1778)
							(mid 0.249642 -0.249642)
							(end 0.1778 -0.2794)
						)
					)
					(width 0)
					(fill yes)
				)
			)
		)
		(pad "2" smd custom
			(at 0 0.4445 180)
			(size 0.1397 0.1397)
			(layers "F.Cu" "F.Mask" "F.Paste")
			(net "TRAY_MBP_CTRL_EN_N")
			(options
				(clearance outline)
				(anchor circle)
			)
			(primitives
				(gr_poly
					(pts
						(arc
							(start -0.1778 -0.2794)
							(mid -0.249642 -0.249642)
							(end -0.2794 -0.1778)
						)
						(arc
							(start -0.2794 0.1778)
							(mid -0.249642 0.249642)
							(end -0.1778 0.2794)
						)
						(arc
							(start 0.1778 0.2794)
							(mid 0.249642 0.249642)
							(end 0.2794 0.1778)
						)
						(arc
							(start 0.2794 -0.1778)
							(mid 0.249642 -0.249642)
							(end 0.1778 -0.2794)
						)
					)
					(width 0)
					(fill yes)
				)
			)
		)
	)
	(footprint ""
		(layer "F.Cu")
		(at 261.112 -26.289 180)
		(property "Reference" "R745"
			(at 0 0 180)
			(layer "F.SilkS")
			(hide yes)
			(effects
				(font
					(size 1.27 1.27)
				)
			)
		)
		(property "Value" "4K7R2F-GP"
			(at 0.064008 -3.993896 180)
			(unlocked yes)
			(layer "F.Fab")
			(hide yes)
			(effects
				(font
					(size 1.016 1.016)
					(thickness 0.1524)
				)
			)
		)
		(property "Device Type" "R402H16"
			(at 0.064008 -5.517896 180)
			(unlocked yes)
			(layer "F.Fab")
			(hide yes)
			(effects
				(font
					(size 1.016 1.016)
					(thickness 0.1524)
				)
			)
		)
		(duplicate_pad_numbers_are_jumpers no)
		(fp_line
			(start 0.508 -0.9398)
			(end -0.508 -0.9398)
			(stroke
				(width 0.1524)
				(type default)
			)
			(layer "F.SilkS")
		)
		(fp_line
			(start -0.508 -0.9398)
			(end -0.508 0.9398)
			(stroke
				(width 0.1524)
				(type default)
			)
			(layer "F.SilkS")
		)
		(fp_rect
			(start -0.508 0.9398)
			(end 0.508 -0.9398)
			(stroke
				(width 0)
				(type default)
			)
			(fill no)
			(layer "F.CrtYd")
		)
		(fp_rect
			(start -0.508 0.9398)
			(end 0.508 -0.9398)
			(stroke
				(width 0)
				(type default)
			)
			(fill no)
			(layer "F.Fab")
		)
		(pad "1" smd custom
			(at 0 -0.4445 180)
			(size 0.1397 0.1397)
			(layers "F.Cu" "F.Mask" "F.Paste")
			(net "P3V3_GPIO")
			(options
				(clearance outline)
				(anchor circle)
			)
			(primitives
				(gr_poly
					(pts
						(arc
							(start -0.1778 -0.2794)
							(mid -0.249642 -0.249642)
							(end -0.2794 -0.1778)
						)
						(arc
							(start -0.2794 0.1778)
							(mid -0.249642 0.249642)
							(end -0.1778 0.2794)
						)
						(arc
							(start 0.1778 0.2794)
							(mid 0.249642 0.249642)
							(end 0.2794 0.1778)
						)
						(arc
							(start 0.2794 -0.1778)
							(mid 0.249642 -0.249642)
							(end 0.1778 -0.2794)
						)
					)
					(width 0)
					(fill yes)
				)
			)
		)
		(pad "2" smd custom
			(at 0 0.4445 180)
			(size 0.1397 0.1397)
			(layers "F.Cu" "F.Mask" "F.Paste")
			(net "IOEXP_INT#_4")
			(options
				(clearance outline)
				(anchor circle)
			)
			(primitives
				(gr_poly
					(pts
						(arc
							(start -0.1778 -0.2794)
							(mid -0.249642 -0.249642)
							(end -0.2794 -0.1778)
						)
						(arc
							(start -0.2794 0.1778)
							(mid -0.249642 0.249642)
							(end -0.1778 0.2794)
						)
						(arc
							(start 0.1778 0.2794)
							(mid 0.249642 0.249642)
							(end 0.2794 0.1778)
						)
						(arc
							(start 0.2794 -0.1778)
							(mid 0.249642 -0.249642)
							(end 0.1778 -0.2794)
						)
					)
					(width 0)
					(fill yes)
				)
			)
		)
	)
	(footprint ""
		(layer "F.Cu")
		(at 265.599926 -17.500092 90)
		(property "Reference" "LED21"
			(at 0 0 90)
			(layer "F.SilkS")
			(hide yes)
			(effects
				(font
					(size 1.27 1.27)
				)
			)
		)
		(property "Value" "LED-YG-51-GP"
			(at -2.6924 -1.4224 90)
			(unlocked yes)
			(layer "F.Fab")
			(hide yes)
			(effects
				(font
					(size 1.016 1.016)
					(thickness 0.1524)
				)
			)
		)
		(property "Device Type" "LED1608AKH40"
			(at -2.6924 -2.9464 90)
			(unlocked yes)
			(layer "F.Fab")
			(hide yes)
			(effects
				(font
					(size 1.016 1.016)
					(thickness 0.1524)
				)
			)
		)
		(duplicate_pad_numbers_are_jumpers no)
		(fp_line
			(start 0.6604 -1.3716)
			(end 0.6604 1.3716)
			(stroke
				(width 0.1524)
				(type default)
			)
			(layer "F.SilkS")
		)
		(fp_line
			(start -0.6604 -1.3716)
			(end 0.6604 -1.3716)
			(stroke
				(width 0.1524)
				(type default)
			)
			(layer "F.SilkS")
		)
		(fp_line
			(start 0.6604 1.3716)
			(end -0.6604 1.3716)
			(stroke
				(width 0.1524)
				(type default)
			)
			(layer "F.SilkS")
		)
		(fp_line
			(start -0.6604 1.3716)
			(end -0.6604 -1.3716)
			(stroke
				(width 0.1524)
				(type default)
			)
			(layer "F.SilkS")
		)
		(fp_line
			(start -0.5969 1.5494)
			(end 0.5842 1.5494)
			(stroke
				(width 0.508)
				(type default)
			)
			(layer "F.SilkS")
		)
		(fp_line
			(start 0.7493 1.651)
			(end 0.7493 1.1811)
			(stroke
				(width 0.3302)
				(type default)
			)
			(layer "F.SilkS")
		)
		(fp_line
			(start -0.7493 1.651)
			(end -0.7493 1.1811)
			(stroke
				(width 0.3302)
				(type default)
			)
			(layer "F.SilkS")
		)
		(fp_rect
			(start -0.6223 1.3335)
			(end 0.6223 -1.3335)
			(stroke
				(width 0)
				(type default)
			)
			(fill no)
			(layer "F.CrtYd")
		)
		(fp_rect
			(start -0.6223 1.3335)
			(end 0.6223 -1.3335)
			(stroke
				(width 0)
				(type default)
			)
			(fill no)
			(layer "F.Fab")
		)
		(pad "A" smd custom
			(at 0 -0.762 90)
			(size 0.2159 0.2159)
			(layers "F.Cu" "F.Mask" "F.Paste")
			(net "LED_R_12")
			(options
				(clearance outline)
				(anchor circle)
			)
			(primitives
				(gr_poly
					(pts
						(arc
							(start -0.3302 -0.4318)
							(mid -0.402042 -0.402042)
							(end -0.4318 -0.3302)
						)
						(arc
							(start -0.4318 0.3302)
							(mid -0.402042 0.402042)
							(end -0.3302 0.4318)
						)
						(arc
							(start 0.3302 0.4318)
							(mid 0.402042 0.402042)
							(end 0.4318 0.3302)
						)
						(arc
							(start 0.4318 -0.3302)
							(mid 0.402042 -0.402042)
							(end 0.3302 -0.4318)
						)
					)
					(width 0)
					(fill yes)
				)
			)
		)
		(pad "K" smd custom
			(at 0 0.762 90)
			(size 0.2159 0.2159)
			(layers "F.Cu" "F.Mask" "F.Paste")
			(net "LED_Q_12")
			(options
				(clearance outline)
				(anchor circle)
			)
			(primitives
				(gr_poly
					(pts
						(arc
							(start -0.3302 -0.4318)
							(mid -0.402042 -0.402042)
							(end -0.4318 -0.3302)
						)
						(arc
							(start -0.4318 0.3302)
							(mid -0.402042 0.402042)
							(end -0.3302 0.4318)
						)
						(arc
							(start 0.3302 0.4318)
							(mid 0.402042 0.402042)
							(end 0.4318 0.3302)
						)
						(arc
							(start 0.4318 -0.3302)
							(mid 0.402042 -0.402042)
							(end 0.3302 -0.4318)
						)
					)
					(width 0)
					(fill yes)
				)
			)
		)
	)
	(footprint ""
		(layer "F.Cu")
		(at 53.721 -133.477 -90)
		(property "Reference" "R319"
			(at 0 0 270)
			(layer "F.SilkS")
			(hide yes)
			(effects
				(font
					(size 1.27 1.27)
				)
			)
		)
		(property "Value" "0R2J-2-GP"
			(at 0.064008 -3.993896 270)
			(unlocked yes)
			(layer "F.Fab")
			(hide yes)
			(effects
				(font
					(size 1.016 1.016)
					(thickness 0.1524)
				)
			)
		)
		(property "Device Type" "R402H16"
			(at 0.064008 -5.517896 270)
			(unlocked yes)
			(layer "F.Fab")
			(hide yes)
			(effects
				(font
					(size 1.016 1.016)
					(thickness 0.1524)
				)
			)
		)
		(duplicate_pad_numbers_are_jumpers no)
		(fp_line
			(start -0.508 -0.9398)
			(end -0.508 0.9398)
			(stroke
				(width 0.1524)
				(type default)
			)
			(layer "F.SilkS")
		)
		(fp_line
			(start 0.508 -0.9398)
			(end -0.508 -0.9398)
			(stroke
				(width 0.1524)
				(type default)
			)
			(layer "F.SilkS")
		)
		(fp_rect
			(start -0.508 0.9398)
			(end 0.508 -0.9398)
			(stroke
				(width 0)
				(type default)
			)
			(fill no)
			(layer "F.CrtYd")
		)
		(fp_rect
			(start -0.508 0.9398)
			(end 0.508 -0.9398)
			(stroke
				(width 0)
				(type default)
			)
			(fill no)
			(layer "F.Fab")
		)
		(pad "1" smd custom
			(at 0 -0.4445 270)
			(size 0.1397 0.1397)
			(layers "F.Cu" "F.Mask" "F.Paste")
			(net "ADC_P1V8_STBY")
			(options
				(clearance outline)
				(anchor circle)
			)
			(primitives
				(gr_poly
					(pts
						(arc
							(start -0.1778 -0.2794)
							(mid -0.249642 -0.249642)
							(end -0.2794 -0.1778)
						)
						(arc
							(start -0.2794 0.1778)
							(mid -0.249642 0.249642)
							(end -0.1778 0.2794)
						)
						(arc
							(start 0.1778 0.2794)
							(mid 0.249642 0.249642)
							(end 0.2794 0.1778)
						)
						(arc
							(start 0.2794 -0.1778)
							(mid 0.249642 -0.249642)
							(end 0.1778 -0.2794)
						)
					)
					(width 0)
					(fill yes)
				)
			)
		)
		(pad "2" smd custom
			(at 0 0.4445 270)
			(size 0.1397 0.1397)
			(layers "F.Cu" "F.Mask" "F.Paste")
			(net "ADC_P1V8_STBY_BMC")
			(options
				(clearance outline)
				(anchor circle)
			)
			(primitives
				(gr_poly
					(pts
						(arc
							(start -0.1778 -0.2794)
							(mid -0.249642 -0.249642)
							(end -0.2794 -0.1778)
						)
						(arc
							(start -0.2794 0.1778)
							(mid -0.249642 0.249642)
							(end -0.1778 0.2794)
						)
						(arc
							(start 0.1778 0.2794)
							(mid 0.249642 0.249642)
							(end 0.2794 0.1778)
						)
						(arc
							(start 0.2794 -0.1778)
							(mid 0.249642 -0.249642)
							(end 0.1778 -0.2794)
						)
					)
					(width 0)
					(fill yes)
				)
			)
		)
	)
	(footprint ""
		(layer "F.Cu")
		(at 147.992084 -212.420454 180)
		(property "Reference" "C273"
			(at 0 0 180)
			(layer "F.SilkS")
			(hide yes)
			(effects
				(font
					(size 1.27 1.27)
				)
			)
		)
		(property "Value" "SCD22U10V2KX-1GP"
			(at 1.1811 -2.7051 180)
			(unlocked yes)
			(layer "F.Fab")
			(hide yes)
			(effects
				(font
					(size 1.016 1.016)
					(thickness 0.1524)
				)
			)
		)
		(property "Device Type" "C402H22"
			(at 1.1811 -4.2291 180)
			(unlocked yes)
			(layer "F.Fab")
			(hide yes)
			(effects
				(font
					(size 1.016 1.016)
					(thickness 0.1524)
				)
			)
		)
		(duplicate_pad_numbers_are_jumpers no)
		(fp_rect
			(start -0.4318 0.9525)
			(end 0.4318 -0.9525)
			(stroke
				(width 0)
				(type default)
			)
			(fill no)
			(layer "F.CrtYd")
		)
		(fp_rect
			(start -0.4318 0.9525)
			(end 0.4318 -0.9525)
			(stroke
				(width 0)
				(type default)
			)
			(fill no)
			(layer "F.Fab")
		)
		(pad "1" smd custom
			(at 0 -0.4445 180)
			(size 0.1524 0.1524)
			(layers "F.Cu" "F.Mask" "F.Paste")
			(net "PCIE_TX_CAP_P56")
			(options
				(clearance outline)
				(anchor circle)
			)
			(primitives
				(gr_poly
					(pts
						(arc
							(start 0.3048 -0.2032)
							(mid 0.275042 -0.275042)
							(end 0.2032 -0.3048)
						)
						(arc
							(start -0.2032 -0.3048)
							(mid -0.275042 -0.275042)
							(end -0.3048 -0.2032)
						)
						(arc
							(start -0.3048 0.2032)
							(mid -0.275042 0.275042)
							(end -0.2032 0.3048)
						)
						(arc
							(start 0.2032 0.3048)
							(mid 0.275042 0.275042)
							(end 0.3048 0.2032)
						)
					)
					(width 0)
					(fill yes)
				)
			)
		)
		(pad "2" smd custom
			(at 0 0.4445 180)
			(size 0.1524 0.1524)
			(layers "F.Cu" "F.Mask" "F.Paste")
			(net "PCIE_TX_P56")
			(options
				(clearance outline)
				(anchor circle)
			)
			(primitives
				(gr_poly
					(pts
						(arc
							(start 0.3048 -0.2032)
							(mid 0.275042 -0.275042)
							(end 0.2032 -0.3048)
						)
						(arc
							(start -0.2032 -0.3048)
							(mid -0.275042 -0.275042)
							(end -0.3048 -0.2032)
						)
						(arc
							(start -0.3048 0.2032)
							(mid -0.275042 0.275042)
							(end -0.2032 0.3048)
						)
						(arc
							(start 0.2032 0.3048)
							(mid 0.275042 0.275042)
							(end 0.3048 0.2032)
						)
					)
					(width 0)
					(fill yes)
				)
			)
		)
	)
	(footprint ""
		(layer "F.Cu")
		(at 36.068 -115.57)
		(property "Reference" "R630"
			(at 0 0 0)
			(layer "F.SilkS")
			(hide yes)
			(effects
				(font
					(size 1.27 1.27)
				)
			)
		)
		(property "Value" "0R2J-2-GP"
			(at 0.064008 -3.993896 0)
			(unlocked yes)
			(layer "F.Fab")
			(hide yes)
			(effects
				(font
					(size 1.016 1.016)
					(thickness 0.1524)
				)
			)
		)
		(property "Device Type" "R402H16"
			(at 0.064008 -5.517896 0)
			(unlocked yes)
			(layer "F.Fab")
			(hide yes)
			(effects
				(font
					(size 1.016 1.016)
					(thickness 0.1524)
				)
			)
		)
		(duplicate_pad_numbers_are_jumpers no)
		(fp_line
			(start -0.508 -0.9398)
			(end -0.508 0.9398)
			(stroke
				(width 0.1524)
				(type default)
			)
			(layer "F.SilkS")
		)
		(fp_line
			(start 0.508 -0.9398)
			(end -0.508 -0.9398)
			(stroke
				(width 0.1524)
				(type default)
			)
			(layer "F.SilkS")
		)
		(fp_rect
			(start -0.508 0.9398)
			(end 0.508 -0.9398)
			(stroke
				(width 0)
				(type default)
			)
			(fill no)
			(layer "F.CrtYd")
		)
		(fp_rect
			(start -0.508 0.9398)
			(end 0.508 -0.9398)
			(stroke
				(width 0)
				(type default)
			)
			(fill no)
			(layer "F.Fab")
		)
		(pad "1" smd custom
			(at 0 -0.4445)
			(size 0.1397 0.1397)
			(layers "F.Cu" "F.Mask" "F.Paste")
			(net "FM_TPM_PRES_N_R")
			(options
				(clearance outline)
				(anchor circle)
			)
			(primitives
				(gr_poly
					(pts
						(arc
							(start -0.1778 -0.2794)
							(mid -0.249642 -0.249642)
							(end -0.2794 -0.1778)
						)
						(arc
							(start -0.2794 0.1778)
							(mid -0.249642 0.249642)
							(end -0.1778 0.2794)
						)
						(arc
							(start 0.1778 0.2794)
							(mid 0.249642 0.249642)
							(end 0.2794 0.1778)
						)
						(arc
							(start 0.2794 -0.1778)
							(mid 0.249642 -0.249642)
							(end 0.1778 -0.2794)
						)
					)
					(width 0)
					(fill yes)
				)
			)
		)
		(pad "2" smd custom
			(at 0 0.4445)
			(size 0.1397 0.1397)
			(layers "F.Cu" "F.Mask" "F.Paste")
			(net "FM_TPM_PRES_N")
			(options
				(clearance outline)
				(anchor circle)
			)
			(primitives
				(gr_poly
					(pts
						(arc
							(start -0.1778 -0.2794)
							(mid -0.249642 -0.249642)
							(end -0.2794 -0.1778)
						)
						(arc
							(start -0.2794 0.1778)
							(mid -0.249642 0.249642)
							(end -0.1778 0.2794)
						)
						(arc
							(start 0.1778 0.2794)
							(mid 0.249642 0.249642)
							(end 0.2794 0.1778)
						)
						(arc
							(start 0.2794 -0.1778)
							(mid 0.249642 -0.249642)
							(end 0.1778 -0.2794)
						)
					)
					(width 0)
					(fill yes)
				)
			)
		)
	)
)
